(kicad_pcb
	(version 20260206)
	(generator "pcbnew")
	(generator_version "10.0")
	(general
		(thickness 1.6)
		(legacy_teardrops no)
	)
	(paper "A4")
	(title_block
		(title "04192023_DAF0TMB3IC0_F0TG_MB_C_brd_V02_OCP.brd")
		(comment 1 "Grand Teton / footprints 5488-5495 of 8354")
	)
	(layers
		(0 "F.Cu" signal "TOP")
		(4 "In1.Cu" signal "GND")
		(6 "In2.Cu" signal "IN1")
		(8 "In3.Cu" signal "GND1")
		(10 "In4.Cu" signal "IN2")
		(12 "In5.Cu" signal "GND2")
		(14 "In6.Cu" signal "IN3")
		(16 "In7.Cu" signal "GND3")
		(18 "In8.Cu" signal "VCC")
		(20 "In9.Cu" signal "VCC1")
		(22 "In10.Cu" signal "GND4")
		(24 "In11.Cu" signal "IN4")
		(26 "In12.Cu" signal "GND5")
		(28 "In13.Cu" signal "IN5")
		(30 "In14.Cu" signal "GND6")
		(32 "In15.Cu" signal "IN6")
		(34 "In16.Cu" signal "GND7")
		(2 "B.Cu" signal "BOTTOM")
		(9 "F.Adhes" user "F.Adhesive")
		(11 "B.Adhes" user "B.Adhesive")
		(13 "F.Paste" user "Package Geometry/Pastemask Top")
		(15 "B.Paste" user "Package Geometry/Pastemask Bottom")
		(5 "F.SilkS" user "Ref Des/Silkscreen Top")
		(7 "B.SilkS" user "Ref Des/Silkscreen Bottom")
		(1 "F.Mask" user "Board Geometry/Soldermask Top")
		(3 "B.Mask" user "Board Geometry/Soldermask Bottom")
		(17 "Dwgs.User" user "User.Drawings")
		(19 "Cmts.User" user "User.Comments")
		(21 "Eco1.User" user "User.Eco1")
		(23 "Eco2.User" user "User.Eco2")
		(25 "Edge.Cuts" user "Board Geometry/Outline")
		(27 "Margin" user)
		(31 "F.CrtYd" user "Package Geometry/Place Bound Top")
		(29 "B.CrtYd" user "Package Geometry/Place Bound Bottom")
		(35 "F.Fab" user "Ref Des/Assembly Top")
		(33 "B.Fab" user "Ref Des/Assembly Bottom")
	)
	(footprint ""
		(layer "B.Cu")
		(at 365.328454 -253.43231)
		(property "Reference" "C3894"
			(at 0 0 0)
			(layer "B.SilkS")
			(hide yes)
			(effects
				(font
					(size 1.27 1.27)
				)
				(justify mirror)
			)
		)
		(property "Value" ""
			(at 0 0 0)
			(layer "B.Fab")
			(effects
				(font
					(size 1.27 1.27)
				)
				(justify mirror)
			)
		)
		(duplicate_pad_numbers_are_jumpers no)
		(fp_line
			(start -0.7874 -0.4064)
			(end -0.7874 0.4064)
			(stroke
				(width 0.1524)
				(type default)
			)
			(layer "B.SilkS")
		)
		(fp_line
			(start -0.7874 0.4064)
			(end 0.7874 0.4064)
			(stroke
				(width 0.1524)
				(type default)
			)
			(layer "B.SilkS")
		)
		(fp_line
			(start 0.7874 -0.4064)
			(end -0.7874 -0.4064)
			(stroke
				(width 0.1524)
				(type default)
			)
			(layer "B.SilkS")
		)
		(fp_line
			(start 0.7874 0.4064)
			(end 0.7874 -0.4064)
			(stroke
				(width 0.1524)
				(type default)
			)
			(layer "B.SilkS")
		)
		(fp_line
			(start -0.67945 -0.3048)
			(end -0.67945 0.3048)
			(stroke
				(width 0.1)
				(type default)
			)
			(layer "B.Fab")
		)
		(fp_line
			(start -0.67945 0.3048)
			(end -0.120396 0.3048)
			(stroke
				(width 0.1)
				(type default)
			)
			(layer "B.Fab")
		)
		(fp_line
			(start -0.12065 -0.3048)
			(end -0.67945 -0.3048)
			(stroke
				(width 0.1)
				(type default)
			)
			(layer "B.Fab")
		)
		(fp_line
			(start -0.12065 -0.2794)
			(end -0.12065 -0.3048)
			(stroke
				(width 0.1)
				(type default)
			)
			(layer "B.Fab")
		)
		(fp_line
			(start -0.120396 0.2794)
			(end 0.12065 0.2794)
			(stroke
				(width 0.1)
				(type default)
			)
			(layer "B.Fab")
		)
		(fp_line
			(start -0.120396 0.3048)
			(end -0.120396 0.2794)
			(stroke
				(width 0.1)
				(type default)
			)
			(layer "B.Fab")
		)
		(fp_line
			(start 0.12065 -0.305054)
			(end 0.12065 -0.2794)
			(stroke
				(width 0.1)
				(type default)
			)
			(layer "B.Fab")
		)
		(fp_line
			(start 0.12065 -0.2794)
			(end -0.12065 -0.2794)
			(stroke
				(width 0.1)
				(type default)
			)
			(layer "B.Fab")
		)
		(fp_line
			(start 0.12065 0.2794)
			(end 0.12065 0.3048)
			(stroke
				(width 0.1)
				(type default)
			)
			(layer "B.Fab")
		)
		(fp_line
			(start 0.12065 0.3048)
			(end 0.67945 0.3048)
			(stroke
				(width 0.1)
				(type default)
			)
			(layer "B.Fab")
		)
		(fp_line
			(start 0.67945 -0.305054)
			(end 0.12065 -0.305054)
			(stroke
				(width 0.1)
				(type default)
			)
			(layer "B.Fab")
		)
		(fp_line
			(start 0.67945 0.3048)
			(end 0.67945 -0.305054)
			(stroke
				(width 0.1)
				(type default)
			)
			(layer "B.Fab")
		)
		(pad "1" smd circle
			(at 0.40005 0 180)
			(size 0 0)
			(layers "B.Cu" "B.Mask" "B.Paste")
			(net "PVDDCR_SOC_P0")
		)
		(pad "2" smd circle
			(at -0.40005 0 180)
			(size 0 0)
			(layers "B.Cu" "B.Mask" "B.Paste")
			(net "GND")
		)
	)
	(footprint ""
		(layer "B.Cu")
		(at 65.825878 -177.349912 90)
		(property "Reference" "PC135_6"
			(at 0 0 90)
			(layer "B.SilkS")
			(hide yes)
			(effects
				(font
					(size 1.27 1.27)
				)
				(justify mirror)
			)
		)
		(property "Value" ""
			(at 0 0 90)
			(layer "B.Fab")
			(effects
				(font
					(size 1.27 1.27)
				)
				(justify mirror)
			)
		)
		(duplicate_pad_numbers_are_jumpers no)
		(fp_line
			(start 1.524 -0.762)
			(end -1.524 -0.762)
			(stroke
				(width 0.1524)
				(type default)
			)
			(layer "B.SilkS")
		)
		(fp_line
			(start -1.524 -0.762)
			(end -1.524 0.762)
			(stroke
				(width 0.1524)
				(type default)
			)
			(layer "B.SilkS")
		)
		(fp_line
			(start 1.524 0.762)
			(end 1.524 -0.762)
			(stroke
				(width 0.1524)
				(type default)
			)
			(layer "B.SilkS")
		)
		(fp_line
			(start -1.524 0.762)
			(end 1.524 0.762)
			(stroke
				(width 0.1524)
				(type default)
			)
			(layer "B.SilkS")
		)
		(fp_line
			(start 1.1049 -0.724916)
			(end 1.1049 0.724916)
			(stroke
				(width 0.1)
				(type default)
			)
			(layer "B.Fab")
		)
		(fp_line
			(start -1.1049 -0.724916)
			(end 1.1049 -0.724916)
			(stroke
				(width 0.1)
				(type default)
			)
			(layer "B.Fab")
		)
		(fp_line
			(start 1.1049 0.724916)
			(end -1.1049 0.724916)
			(stroke
				(width 0.1)
				(type default)
			)
			(layer "B.Fab")
		)
		(fp_line
			(start -1.1049 0.724916)
			(end -1.1049 -0.724916)
			(stroke
				(width 0.1)
				(type default)
			)
			(layer "B.Fab")
		)
		(pad "1" smd rect
			(at 0.889 0 90)
			(size 1.016 1.27)
			(layers "B.Cu" "B.Mask" "B.Paste")
			(net "PVDDCR_CPU0_P1")
		)
		(pad "2" smd rect
			(at -0.889 0 90)
			(size 1.016 1.27)
			(layers "B.Cu" "B.Mask" "B.Paste")
			(net "GND")
		)
	)
	(footprint ""
		(layer "B.Cu")
		(at 349.245936 -396.393162 -90)
		(property "Reference" "C623"
			(at 0 0 90)
			(layer "B.SilkS")
			(hide yes)
			(effects
				(font
					(size 1.27 1.27)
				)
				(justify mirror)
			)
		)
		(property "Value" ""
			(at 0 0 90)
			(layer "B.Fab")
			(effects
				(font
					(size 1.27 1.27)
				)
				(justify mirror)
			)
		)
		(duplicate_pad_numbers_are_jumpers no)
		(fp_line
			(start -0.299974 0.150114)
			(end 0.299974 0.150114)
			(stroke
				(width 0.1)
				(type default)
			)
			(layer "B.Fab")
		)
		(fp_line
			(start 0.299974 0.150114)
			(end 0.299974 -0.150114)
			(stroke
				(width 0.1)
				(type default)
			)
			(layer "B.Fab")
		)
		(fp_line
			(start -0.299974 -0.150114)
			(end -0.299974 0.150114)
			(stroke
				(width 0.1)
				(type default)
			)
			(layer "B.Fab")
		)
		(fp_line
			(start 0.299974 -0.150114)
			(end -0.299974 -0.150114)
			(stroke
				(width 0.1)
				(type default)
			)
			(layer "B.Fab")
		)
		(pad "1" smd rect
			(at 0.2667 0 90)
			(size 0.3048 0.381)
			(layers "B.Cu" "B.Mask" "B.Paste")
			(net "P0V9_CPU0_RT1_2A_2D")
		)
		(pad "2" smd rect
			(at -0.2667 0 90)
			(size 0.3048 0.381)
			(layers "B.Cu" "B.Mask" "B.Paste")
			(net "GND")
		)
	)
	(footprint ""
		(layer "B.Cu")
		(at 52.782978 -429.84293 90)
		(property "Reference" "R3487"
			(at 0 0 90)
			(layer "B.SilkS")
			(hide yes)
			(effects
				(font
					(size 1.27 1.27)
				)
				(justify mirror)
			)
		)
		(property "Value" ""
			(at 0 0 90)
			(layer "B.Fab")
			(effects
				(font
					(size 1.27 1.27)
				)
				(justify mirror)
			)
		)
		(duplicate_pad_numbers_are_jumpers no)
		(fp_line
			(start 0.7874 -0.4064)
			(end -0.7874 -0.4064)
			(stroke
				(width 0.1524)
				(type default)
			)
			(layer "B.SilkS")
		)
		(fp_line
			(start -0.7874 -0.4064)
			(end -0.7874 0.4064)
			(stroke
				(width 0.1524)
				(type default)
			)
			(layer "B.SilkS")
		)
		(fp_line
			(start 0.7874 0.4064)
			(end 0.7874 -0.4064)
			(stroke
				(width 0.1524)
				(type default)
			)
			(layer "B.SilkS")
		)
		(fp_line
			(start -0.7874 0.4064)
			(end 0.7874 0.4064)
			(stroke
				(width 0.1524)
				(type default)
			)
			(layer "B.SilkS")
		)
		(fp_line
			(start 0.67945 -0.305054)
			(end 0.12065 -0.305054)
			(stroke
				(width 0.1)
				(type default)
			)
			(layer "B.Fab")
		)
		(fp_line
			(start 0.12065 -0.305054)
			(end 0.12065 -0.2794)
			(stroke
				(width 0.1)
				(type default)
			)
			(layer "B.Fab")
		)
		(fp_line
			(start -0.12065 -0.3048)
			(end -0.67945 -0.3048)
			(stroke
				(width 0.1)
				(type default)
			)
			(layer "B.Fab")
		)
		(fp_line
			(start -0.67945 -0.3048)
			(end -0.67945 0.3048)
			(stroke
				(width 0.1)
				(type default)
			)
			(layer "B.Fab")
		)
		(fp_line
			(start 0.12065 -0.2794)
			(end -0.12065 -0.2794)
			(stroke
				(width 0.1)
				(type default)
			)
			(layer "B.Fab")
		)
		(fp_line
			(start -0.12065 -0.2794)
			(end -0.12065 -0.3048)
			(stroke
				(width 0.1)
				(type default)
			)
			(layer "B.Fab")
		)
		(fp_line
			(start 0.12065 0.2794)
			(end 0.12065 0.3048)
			(stroke
				(width 0.1)
				(type default)
			)
			(layer "B.Fab")
		)
		(fp_line
			(start -0.120396 0.2794)
			(end 0.12065 0.2794)
			(stroke
				(width 0.1)
				(type default)
			)
			(layer "B.Fab")
		)
		(fp_line
			(start 0.67945 0.3048)
			(end 0.67945 -0.305054)
			(stroke
				(width 0.1)
				(type default)
			)
			(layer "B.Fab")
		)
		(fp_line
			(start 0.12065 0.3048)
			(end 0.67945 0.3048)
			(stroke
				(width 0.1)
				(type default)
			)
			(layer "B.Fab")
		)
		(fp_line
			(start -0.120396 0.3048)
			(end -0.120396 0.2794)
			(stroke
				(width 0.1)
				(type default)
			)
			(layer "B.Fab")
		)
		(fp_line
			(start -0.67945 0.3048)
			(end -0.120396 0.3048)
			(stroke
				(width 0.1)
				(type default)
			)
			(layer "B.Fab")
		)
		(pad "1" smd circle
			(at 0.40005 0 270)
			(size 0 0)
			(layers "B.Cu" "B.Mask" "B.Paste")
			(net "P3V3_AUX")
		)
		(pad "2" smd circle
			(at -0.40005 0 270)
			(size 0 0)
			(layers "B.Cu" "B.Mask" "B.Paste")
			(net "GPU_PRSNT_N")
		)
	)
	(footprint ""
		(layer "B.Cu")
		(at 36.796218 -192.66027)
		(property "Reference" "C181"
			(at 0 0 0)
			(layer "B.SilkS")
			(hide yes)
			(effects
				(font
					(size 1.27 1.27)
				)
				(justify mirror)
			)
		)
		(property "Value" ""
			(at 0 0 0)
			(layer "B.Fab")
			(effects
				(font
					(size 1.27 1.27)
				)
				(justify mirror)
			)
		)
		(duplicate_pad_numbers_are_jumpers no)
		(fp_line
			(start -1.524 -0.762)
			(end -1.524 0.762)
			(stroke
				(width 0.1524)
				(type default)
			)
			(layer "B.SilkS")
		)
		(fp_line
			(start -1.524 0.762)
			(end 1.524 0.762)
			(stroke
				(width 0.1524)
				(type default)
			)
			(layer "B.SilkS")
		)
		(fp_line
			(start 1.524 -0.762)
			(end -1.524 -0.762)
			(stroke
				(width 0.1524)
				(type default)
			)
			(layer "B.SilkS")
		)
		(fp_line
			(start 1.524 0.762)
			(end 1.524 -0.762)
			(stroke
				(width 0.1524)
				(type default)
			)
			(layer "B.SilkS")
		)
		(fp_line
			(start -1.1049 -0.724916)
			(end 1.1049 -0.724916)
			(stroke
				(width 0.1)
				(type default)
			)
			(layer "B.Fab")
		)
		(fp_line
			(start -1.1049 0.724916)
			(end -1.1049 -0.724916)
			(stroke
				(width 0.1)
				(type default)
			)
			(layer "B.Fab")
		)
		(fp_line
			(start 1.1049 -0.724916)
			(end 1.1049 0.724916)
			(stroke
				(width 0.1)
				(type default)
			)
			(layer "B.Fab")
		)
		(fp_line
			(start 1.1049 0.724916)
			(end -1.1049 0.724916)
			(stroke
				(width 0.1)
				(type default)
			)
			(layer "B.Fab")
		)
		(pad "1" smd rect
			(at 0.889 0)
			(size 1.016 1.27)
			(layers "B.Cu" "B.Mask" "B.Paste")
			(net "P12V_MEM_CPU1")
		)
		(pad "2" smd rect
			(at -0.889 0)
			(size 1.016 1.27)
			(layers "B.Cu" "B.Mask" "B.Paste")
			(net "GND")
		)
	)
	(footprint ""
		(layer "B.Cu")
		(at 299.06849 -195.859146 180)
		(property "Reference" "R1675"
			(at 0 0 0)
			(layer "B.SilkS")
			(hide yes)
			(effects
				(font
					(size 1.27 1.27)
				)
				(justify mirror)
			)
		)
		(property "Value" ""
			(at 0 0 0)
			(layer "B.Fab")
			(effects
				(font
					(size 1.27 1.27)
				)
				(justify mirror)
			)
		)
		(duplicate_pad_numbers_are_jumpers no)
		(fp_line
			(start 0.7874 0.4064)
			(end 0.7874 -0.4064)
			(stroke
				(width 0.1524)
				(type default)
			)
			(layer "B.SilkS")
		)
		(fp_line
			(start 0.7874 -0.4064)
			(end -0.7874 -0.4064)
			(stroke
				(width 0.1524)
				(type default)
			)
			(layer "B.SilkS")
		)
		(fp_line
			(start -0.7874 0.4064)
			(end 0.7874 0.4064)
			(stroke
				(width 0.1524)
				(type default)
			)
			(layer "B.SilkS")
		)
		(fp_line
			(start -0.7874 -0.4064)
			(end -0.7874 0.4064)
			(stroke
				(width 0.1524)
				(type default)
			)
			(layer "B.SilkS")
		)
		(fp_line
			(start 0.67945 0.3048)
			(end 0.67945 -0.305054)
			(stroke
				(width 0.1)
				(type default)
			)
			(layer "B.Fab")
		)
		(fp_line
			(start 0.67945 -0.305054)
			(end 0.12065 -0.305054)
			(stroke
				(width 0.1)
				(type default)
			)
			(layer "B.Fab")
		)
		(fp_line
			(start 0.12065 0.3048)
			(end 0.67945 0.3048)
			(stroke
				(width 0.1)
				(type default)
			)
			(layer "B.Fab")
		)
		(fp_line
			(start 0.12065 0.2794)
			(end 0.12065 0.3048)
			(stroke
				(width 0.1)
				(type default)
			)
			(layer "B.Fab")
		)
		(fp_line
			(start 0.12065 -0.2794)
			(end -0.12065 -0.2794)
			(stroke
				(width 0.1)
				(type default)
			)
			(layer "B.Fab")
		)
		(fp_line
			(start 0.12065 -0.305054)
			(end 0.12065 -0.2794)
			(stroke
				(width 0.1)
				(type default)
			)
			(layer "B.Fab")
		)
		(fp_line
			(start -0.120396 0.3048)
			(end -0.120396 0.2794)
			(stroke
				(width 0.1)
				(type default)
			)
			(layer "B.Fab")
		)
		(fp_line
			(start -0.120396 0.2794)
			(end 0.12065 0.2794)
			(stroke
				(width 0.1)
				(type default)
			)
			(layer "B.Fab")
		)
		(fp_line
			(start -0.12065 -0.2794)
			(end -0.12065 -0.3048)
			(stroke
				(width 0.1)
				(type default)
			)
			(layer "B.Fab")
		)
		(fp_line
			(start -0.12065 -0.3048)
			(end -0.67945 -0.3048)
			(stroke
				(width 0.1)
				(type default)
			)
			(layer "B.Fab")
		)
		(fp_line
			(start -0.67945 0.3048)
			(end -0.120396 0.3048)
			(stroke
				(width 0.1)
				(type default)
			)
			(layer "B.Fab")
		)
		(fp_line
			(start -0.67945 -0.3048)
			(end -0.67945 0.3048)
			(stroke
				(width 0.1)
				(type default)
			)
			(layer "B.Fab")
		)
		(pad "1" smd circle
			(at 0.40005 0)
			(size 0 0)
			(layers "B.Cu" "B.Mask" "B.Paste")
			(net "I3C_SPD_DDRAF_CPU0_SDA")
		)
		(pad "2" smd circle
			(at -0.40005 0)
			(size 0 0)
			(layers "B.Cu" "B.Mask" "B.Paste")
			(net "I3C_SPD_DDRB_CPU0_SDA")
		)
	)
	(footprint ""
		(layer "B.Cu")
		(at 163.4236 -412.18866 90)
		(property "Reference" "R692"
			(at 0 0 90)
			(layer "B.SilkS")
			(hide yes)
			(effects
				(font
					(size 1.27 1.27)
				)
				(justify mirror)
			)
		)
		(property "Value" ""
			(at 0 0 90)
			(layer "B.Fab")
			(effects
				(font
					(size 1.27 1.27)
				)
				(justify mirror)
			)
		)
		(duplicate_pad_numbers_are_jumpers no)
		(fp_line
			(start 0.32512 -0.175006)
			(end -0.32512 -0.175006)
			(stroke
				(width 0.1)
				(type default)
			)
			(layer "B.Fab")
		)
		(fp_line
			(start -0.32512 -0.175006)
			(end -0.32512 0.175006)
			(stroke
				(width 0.1)
				(type default)
			)
			(layer "B.Fab")
		)
		(fp_line
			(start 0.32512 0.175006)
			(end 0.32512 -0.175006)
			(stroke
				(width 0.1)
				(type default)
			)
			(layer "B.Fab")
		)
		(fp_line
			(start -0.32512 0.175006)
			(end 0.32512 0.175006)
			(stroke
				(width 0.1)
				(type default)
			)
			(layer "B.Fab")
		)
		(pad "1" smd rect
			(at 0.2667 0 270)
			(size 0.3048 0.381)
			(layers "B.Cu" "B.Mask" "B.Paste")
			(net "SMB_RT_CPU1_P2_ROM_MUX_1D_SDA")
		)
		(pad "2" smd rect
			(at -0.2667 0 90)
			(size 0.3048 0.381)
			(layers "B.Cu" "B.Mask" "B.Paste")
			(net "SMB_RT_CPU1_P2_ROM_MUX_1D_R_SDA")
		)
	)
	(footprint ""
		(layer "B.Cu")
		(at 332.748128 -336.032856 -90)
		(property "Reference" "PR79"
			(at 0 0 90)
			(layer "B.SilkS")
			(hide yes)
			(effects
				(font
					(size 1.27 1.27)
				)
				(justify mirror)
			)
		)
		(property "Value" ""
			(at 0 0 90)
			(layer "B.Fab")
			(effects
				(font
					(size 1.27 1.27)
				)
				(justify mirror)
			)
		)
		(duplicate_pad_numbers_are_jumpers no)
		(fp_line
			(start -0.7874 0.4064)
			(end 0.7874 0.4064)
			(stroke
				(width 0.1524)
				(type default)
			)
			(layer "B.SilkS")
		)
		(fp_line
			(start 0.7874 0.4064)
			(end 0.7874 -0.4064)
			(stroke
				(width 0.1524)
				(type default)
			)
			(layer "B.SilkS")
		)
		(fp_line
			(start -0.7874 -0.4064)
			(end -0.7874 0.4064)
			(stroke
				(width 0.1524)
				(type default)
			)
			(layer "B.SilkS")
		)
		(fp_line
			(start 0.7874 -0.4064)
			(end -0.7874 -0.4064)
			(stroke
				(width 0.1524)
				(type default)
			)
			(layer "B.SilkS")
		)
		(fp_line
			(start -0.67945 0.3048)
			(end -0.120396 0.3048)
			(stroke
				(width 0.1)
				(type default)
			)
			(layer "B.Fab")
		)
		(fp_line
			(start -0.120396 0.3048)
			(end -0.120396 0.2794)
			(stroke
				(width 0.1)
				(type default)
			)
			(layer "B.Fab")
		)
		(fp_line
			(start 0.12065 0.3048)
			(end 0.67945 0.3048)
			(stroke
				(width 0.1)
				(type default)
			)
			(layer "B.Fab")
		)
		(fp_line
			(start 0.67945 0.3048)
			(end 0.67945 -0.305054)
			(stroke
				(width 0.1)
				(type default)
			)
			(layer "B.Fab")
		)
		(fp_line
			(start -0.120396 0.2794)
			(end 0.12065 0.2794)
			(stroke
				(width 0.1)
				(type default)
			)
			(layer "B.Fab")
		)
		(fp_line
			(start 0.12065 0.2794)
			(end 0.12065 0.3048)
			(stroke
				(width 0.1)
				(type default)
			)
			(layer "B.Fab")
		)
		(fp_line
			(start -0.12065 -0.2794)
			(end -0.12065 -0.3048)
			(stroke
				(width 0.1)
				(type default)
			)
			(layer "B.Fab")
		)
		(fp_line
			(start 0.12065 -0.2794)
			(end -0.12065 -0.2794)
			(stroke
				(width 0.1)
				(type default)
			)
			(layer "B.Fab")
		)
		(fp_line
			(start -0.67945 -0.3048)
			(end -0.67945 0.3048)
			(stroke
				(width 0.1)
				(type default)
			)
			(layer "B.Fab")
		)
		(fp_line
			(start -0.12065 -0.3048)
			(end -0.67945 -0.3048)
			(stroke
				(width 0.1)
				(type default)
			)
			(layer "B.Fab")
		)
		(fp_line
			(start 0.12065 -0.305054)
			(end 0.12065 -0.2794)
			(stroke
				(width 0.1)
				(type default)
			)
			(layer "B.Fab")
		)
		(fp_line
			(start 0.67945 -0.305054)
			(end 0.12065 -0.305054)
			(stroke
				(width 0.1)
				(type default)
			)
			(layer "B.Fab")
		)
		(pad "1" smd circle
			(at 0.40005 0 90)
			(size 0 0)
			(layers "B.Cu" "B.Mask" "B.Paste")
			(net "PVDDCR_CPU1_P0_PVCC")
		)
		(pad "2" smd circle
			(at -0.40005 0 90)
			(size 0 0)
			(layers "B.Cu" "B.Mask" "B.Paste")
			(net "PVDDCR_CPU1_P0_VCC1")
		)
	)
)
